(kicad_pcb
	(version 20241229)
	(generator "pcbnew")
	(generator_version "9.0")
	(general
		(thickness 1.711)
		(legacy_teardrops no)
	)
	(paper "A4")
	(title_block
		(title "Antmicro Baseboard for Jetson AGX Thor")
		(date "2026-02-18")
		(rev "1.1.0")
		(company "Antmicro Ltd")
		(comment 1 "www.antmicro.com")
		(comment 9 "footprints 422-424 of 1170")
	)
	(layers
		(0 "F.Cu" signal)
		(4 "In1.Cu" signal)
		(6 "In2.Cu" signal)
		(8 "In3.Cu" signal)
		(10 "In4.Cu" jumper)
		(12 "In5.Cu" signal)
		(14 "In6.Cu" signal)
		(16 "In7.Cu" signal)
		(18 "In8.Cu" signal)
		(2 "B.Cu" signal)
		(9 "F.Adhes" user "F.Adhesive")
		(11 "B.Adhes" user "B.Adhesive")
		(13 "F.Paste" user)
		(15 "B.Paste" user)
		(5 "F.SilkS" user "F.Silkscreen")
		(7 "B.SilkS" user "B.Silkscreen")
		(1 "F.Mask" user)
		(3 "B.Mask" user)
		(17 "Dwgs.User" user "User.Drawings")
		(19 "Cmts.User" user "User.Comments")
		(21 "Eco1.User" user "User.Eco1")
		(23 "Eco2.User" user "User.Eco2")
		(25 "Edge.Cuts" user)
		(27 "Margin" user)
		(31 "F.CrtYd" user "F.Courtyard")
		(29 "B.CrtYd" user "B.Courtyard")
		(35 "F.Fab" user)
		(33 "B.Fab" user)
	)
	(footprint "antmicro-footprints:Vishay_PowerPAK_1212-8_Single"
		(layer "F.Cu")
		(at 216.736 72.512)
		(descr "PowerPAK 1212-8 Single")
		(tags "Vishay PowerPAK 1212-8 Single")
		(property "Reference" "Q33"
			(at 2.914 0.388 90)
			(layer "F.SilkS")
			(effects
				(font
					(size 0.7 0.7)
					(thickness 0.15)
				)
				(justify left bottom)
			)
		)
		(property "Value" "SISS05DN-T1-GE3"
			(at 0 2.7 0)
			(layer "F.Fab")
			(effects
				(font
					(size 0.7 0.7)
					(thickness 0.15)
				)
				(justify left bottom)
			)
		)
		(property "Datasheet" "https://www.vishay.com/docs/77029/siss05dn.pdf"
			(at 0 0 0)
			(layer "F.Fab")
			(hide yes)
			(effects
				(font
					(size 1.27 1.27)
					(thickness 0.15)
				)
			)
		)
		(property "Description" "Power MOSFET, P Channel, 30 V, 108 A, 0.0035 ohm, PowerPAK 1212, Surface Mount"
			(at 0 0 0)
			(layer "F.Fab")
			(hide yes)
			(effects
				(font
					(size 1.27 1.27)
					(thickness 0.15)
				)
			)
		)
		(property "MPN" "SISS05DN-T1-GE3"
			(at 0 0 0)
			(unlocked yes)
			(layer "F.Fab")
			(hide yes)
			(effects
				(font
					(size 1 1)
					(thickness 0.15)
				)
			)
		)
		(property "Manufacturer" "Vishay"
			(at 0 0 0)
			(unlocked yes)
			(layer "F.Fab")
			(hide yes)
			(effects
				(font
					(size 1 1)
					(thickness 0.15)
				)
			)
		)
		(property "Author" "Antmicro"
			(at 0 0 0)
			(unlocked yes)
			(layer "F.Fab")
			(hide yes)
			(effects
				(font
					(size 1 1)
					(thickness 0.15)
				)
			)
		)
		(property "License" "Apache-2.0"
			(at 0 0 0)
			(unlocked yes)
			(layer "F.Fab")
			(hide yes)
			(effects
				(font
					(size 1 1)
					(thickness 0.15)
				)
			)
		)
		(sheetname "/Power/")
		(sheetfile "power.kicad_sch")
		(attr smd)
		(fp_line
			(start -1.651 -1.651)
			(end -1.651 -1.317)
			(stroke
				(width 0.15)
				(type solid)
			)
			(layer "F.SilkS")
		)
		(fp_line
			(start -1.651 -1.651)
			(end 1.648 -1.651)
			(stroke
				(width 0.15)
				(type solid)
			)
			(layer "F.SilkS")
		)
		(fp_line
			(start -1.635 1.3)
			(end -1.635 1.634)
			(stroke
				(width 0.15)
				(type solid)
			)
			(layer "F.SilkS")
		)
		(fp_line
			(start -1.635 1.634)
			(end 1.634 1.634)
			(stroke
				(width 0.15)
				(type solid)
			)
			(layer "F.SilkS")
		)
		(fp_line
			(start 1.634 1.3)
			(end 1.634 1.634)
			(stroke
				(width 0.15)
				(type solid)
			)
			(layer "F.SilkS")
		)
		(fp_line
			(start 1.648 -1.651)
			(end 1.648 -1.317)
			(stroke
				(width 0.15)
				(type solid)
			)
			(layer "F.SilkS")
		)
		(fp_circle
			(center -1.9 -1.4)
			(end -1.85 -1.4)
			(stroke
				(width 0.15)
				(type solid)
			)
			(fill yes)
			(layer "F.SilkS")
		)
		(fp_rect
			(start -2 -1.8)
			(end 2 1.798)
			(stroke
				(width 0.05)
				(type solid)
			)
			(fill no)
			(layer "F.CrtYd")
		)
		(fp_line
			(start -1.6425 -1.4175)
			(end -1.4175 -1.6425)
			(stroke
				(width 0.15)
				(type solid)
			)
			(layer "F.Fab")
		)
		(fp_rect
			(start -1.651 -1.651)
			(end 1.648 1.648)
			(stroke
				(width 0.15)
				(type solid)
			)
			(fill no)
			(layer "F.Fab")
		)
		(fp_text user "Author: Antmicro"
			(at -8 5.9 0)
			(layer "F.Fab")
			(effects
				(font
					(size 0.7 0.7)
					(thickness 0.15)
				)
				(justify left bottom)
			)
		)
		(fp_text user "License: Apache-2.0"
			(at -8 7.1 0)
			(layer "F.Fab")
			(effects
				(font
					(size 0.7 0.7)
					(thickness 0.15)
				)
				(justify left bottom)
			)
		)
		(fp_text user "${REFERENCE}"
			(at -8 4.7 0)
			(layer "F.Fab")
			(effects
				(font
					(size 0.7 0.7)
					(thickness 0.15)
				)
				(justify left bottom)
			)
		)
		(pad "1" smd rect
			(at -1.436 -0.99)
			(size 0.99 0.405)
			(layers "F.Cu" "F.Mask" "F.Paste")
			(net 1383 "VCC_NO_OVP")
			(pinfunction "S")
			(pintype "passive")
		)
		(pad "2" smd rect
			(at -1.436 -0.332)
			(size 0.99 0.405)
			(layers "F.Cu" "F.Mask" "F.Paste")
			(net 1383 "VCC_NO_OVP")
			(pinfunction "S")
			(pintype "passive")
		)
		(pad "3" smd rect
			(at -1.436 0.33)
			(size 0.99 0.405)
			(layers "F.Cu" "F.Mask" "F.Paste")
			(net 1383 "VCC_NO_OVP")
			(pinfunction "S")
			(pintype "passive")
		)
		(pad "4" smd rect
			(at -1.436 0.988)
			(size 0.99 0.405)
			(layers "F.Cu" "F.Mask" "F.Paste")
			(net 1384 "Net-(Q32-G)")
			(pinfunction "G")
			(pintype "input")
		)
		(pad "5" smd custom
			(at 0.557 0)
			(size 1.725 2.235)
			(layers "F.Cu" "F.Mask" "F.Paste")
			(net 3 "VCC_IN")
			(pinfunction "D")
			(pintype "passive")
			(zone_connect 2)
			(options
				(clearance outline)
				(anchor rect)
			)
			(primitives
				(gr_poly
					(pts
						(xy 0.8625 0.1275) (xy 0.8625 -0.1275) (xy 1.3725 -0.1275) (xy 1.3725 -0.5325) (xy 0.8625 -0.5325)
						(xy 0.8625 -0.7875) (xy 1.3725 -0.7875) (xy 1.3725 -1.195) (xy 0.6125 -1.195) (xy 0.6125 1.195)
						(xy 1.3725 1.195) (xy 1.3725 0.7875) (xy 0.8625 0.7875) (xy 0.8625 0.5325) (xy 1.3725 0.5325)
						(xy 1.3725 0.1275)
					)
					(width 0)
					(fill yes)
				)
			)
		)
	)
	(footprint "antmicro-footprints:WQFN-30-1EP_4.6x2.6mm_P0.4mm"
		(layer "F.Cu")
		(at 215.249 102.335)
		(property "Reference" "U56"
			(at -1.149 3.565 0)
			(layer "F.SilkS")
			(effects
				(font
					(size 0.7 0.7)
					(thickness 0.15)
				)
				(justify left bottom)
			)
		)
		(property "Value" "HD3SS3220IRNHR"
			(at 0 3.5 0)
			(layer "F.Fab")
			(effects
				(font
					(size 0.7 0.7)
					(thickness 0.15)
				)
				(justify right top)
			)
		)
		(property "Datasheet" "https://www.ti.com/lit/ds/symlink/hd3ss3220.pdf?ts=1663000043694&ref_url=https%253A%252F%252Fwww.google.com%252F"
			(at 0 0 0)
			(layer "F.Fab")
			(hide yes)
			(effects
				(font
					(size 1.27 1.27)
					(thickness 0.15)
				)
			)
		)
		(property "Description" "USB Interface IC 10-Gbps USB 3.1 Type-C 2:1 mux with DRP Controller 30-WQFN -40°C to 85°C"
			(at 0 0 0)
			(layer "F.Fab")
			(hide yes)
			(effects
				(font
					(size 1.27 1.27)
					(thickness 0.15)
				)
			)
		)
		(property "Manufacturer" "Texas Instruments"
			(at 0 0 0)
			(unlocked yes)
			(layer "F.Fab")
			(hide yes)
			(effects
				(font
					(size 1 1)
					(thickness 0.15)
				)
			)
		)
		(property "MPN" "HD3SS3220IRNHR"
			(at 0 0 0)
			(unlocked yes)
			(layer "F.Fab")
			(hide yes)
			(effects
				(font
					(size 1 1)
					(thickness 0.15)
				)
			)
		)
		(property "Author" "Antmicro"
			(at 0 0 0)
			(unlocked yes)
			(layer "F.Fab")
			(hide yes)
			(effects
				(font
					(size 1 1)
					(thickness 0.15)
				)
			)
		)
		(property "License" "Apache-2.0"
			(at 0 0 0)
			(unlocked yes)
			(layer "F.Fab")
			(hide yes)
			(effects
				(font
					(size 1 1)
					(thickness 0.15)
				)
			)
		)
		(sheetname "/Recovery USB/")
		(sheetfile "recovery_usb.kicad_sch")
		(attr smd)
		(fp_line
			(start -1.253 -2.26)
			(end -1.253 -2.01)
			(stroke
				(width 0.15)
				(type solid)
			)
			(layer "F.SilkS")
		)
		(fp_line
			(start -1.253 -2.26)
			(end -1.003 -2.26)
			(stroke
				(width 0.15)
				(type solid)
			)
			(layer "F.SilkS")
		)
		(fp_line
			(start -1.253 2.24)
			(end -1.253 1.99)
			(stroke
				(width 0.15)
				(type solid)
			)
			(layer "F.SilkS")
		)
		(fp_line
			(start -1.253 2.24)
			(end -1.003 2.24)
			(stroke
				(width 0.15)
				(type solid)
			)
			(layer "F.SilkS")
		)
		(fp_line
			(start 1.247 -2.26)
			(end 0.997 -2.26)
			(stroke
				(width 0.15)
				(type solid)
			)
			(layer "F.SilkS")
		)
		(fp_line
			(start 1.247 -2.26)
			(end 1.247 -2.01)
			(stroke
				(width 0.15)
				(type solid)
			)
			(layer "F.SilkS")
		)
		(fp_line
			(start 1.247 2.24)
			(end 0.997 2.24)
			(stroke
				(width 0.15)
				(type solid)
			)
			(layer "F.SilkS")
		)
		(fp_line
			(start 1.247 2.24)
			(end 1.247 1.99)
			(stroke
				(width 0.15)
				(type solid)
			)
			(layer "F.SilkS")
		)
		(fp_circle
			(center -1.5 -2.5)
			(end -1.45 -2.5)
			(stroke
				(width 0.15)
				(type solid)
			)
			(fill yes)
			(layer "F.SilkS")
		)
		(fp_rect
			(start -1.6 -2.6)
			(end 1.6 2.6)
			(stroke
				(width 0.05)
				(type solid)
			)
			(fill no)
			(layer "F.CrtYd")
		)
		(fp_rect
			(start -1.3 -2.3)
			(end 1.3 2.3)
			(stroke
				(width 0.15)
				(type solid)
			)
			(fill no)
			(layer "F.Fab")
		)
		(fp_text user "${REFERENCE}"
			(at -1.6 4.8 0)
			(layer "F.Fab")
			(effects
				(font
					(size 0.7 0.7)
					(thickness 0.15)
				)
				(justify left bottom)
			)
		)
		(fp_text user "Author: Antmicro"
			(at -1.6 6 0)
			(layer "F.Fab")
			(effects
				(font
					(size 0.7 0.7)
					(thickness 0.15)
				)
				(justify left bottom)
			)
		)
		(fp_text user "License: Apache-2.0"
			(at -1.6 7.199 0)
			(layer "F.Fab")
			(effects
				(font
					(size 0.7 0.7)
					(thickness 0.15)
				)
				(justify left bottom)
			)
		)
		(pad "1" smd rect
			(at -1.232 -1.809 90)
			(size 0.2 0.45)
			(layers "F.Cu" "F.Mask" "F.Paste")
			(net 801 "/Recovery USB/USBC2_CC2")
			(pinfunction "CC2")
			(pintype "passive")
		)
		(pad "2" smd rect
			(at -1.203 -1.41 90)
			(size 0.2 0.5)
			(layers "F.Cu" "F.Mask" "F.Paste")
			(net 806 "/Recovery USB/USBC2_CC1")
			(pinfunction "CC1")
			(pintype "passive")
		)
		(pad "3" smd rect
			(at -1.203 -1.01 90)
			(size 0.2 0.5)
			(layers "F.Cu" "F.Mask" "F.Paste")
			(net 1023 "/Recovery USB/USBC2_I_MODE")
			(pinfunction "CURRENT_MODE")
			(pintype "passive")
		)
		(pad "4" smd rect
			(at -1.203 -0.609 90)
			(size 0.2 0.5)
			(layers "F.Cu" "F.Mask" "F.Paste")
			(net 1012 "/Recovery USB/USBC2_PORT")
			(pinfunction "PORT")
			(pintype "passive")
		)
		(pad "5" smd rect
			(at -1.203 -0.21 90)
			(size 0.2 0.5)
			(layers "F.Cu" "F.Mask" "F.Paste")
			(net 1246 "/Recovery USB/USBC2_VBUS_DET_MUX")
			(pinfunction "VBUS_DET")
			(pintype "passive")
		)
		(pad "6" smd rect
			(at -1.203 0.191 90)
			(size 0.2 0.5)
			(layers "F.Cu" "F.Mask" "F.Paste")
			(net 1131 "/Recovery USB/USBSS_TX_P")
			(pinfunction "TX+")
			(pintype "passive")
		)
		(pad "7" smd rect
			(at -1.203 0.59 90)
			(size 0.2 0.5)
			(layers "F.Cu" "F.Mask" "F.Paste")
			(net 1129 "/Recovery USB/USBSS_TX_N")
			(pinfunction "TX-")
			(pintype "passive")
		)
		(pad "8" smd rect
			(at -1.203 0.99 90)
			(size 0.2 0.5)
			(layers "F.Cu" "F.Mask" "F.Paste")
			(net 2 "+3V3")
			(pinfunction "VCC33")
			(pintype "passive")
		)
		(pad "9" smd rect
			(at -1.203 1.391 90)
			(size 0.2 0.5)
			(layers "F.Cu" "F.Mask" "F.Paste")
			(net 1130 "/Recovery USB/USBSS_RX_P")
			(pinfunction "RX+")
			(pintype "passive")
		)
		(pad "10" smd rect
			(at -1.232 1.79 90)
			(size 0.2 0.45)
			(layers "F.Cu" "F.Mask" "F.Paste")
			(net 1128 "/Recovery USB/USBSS_RX_N")
			(pinfunction "RX-")
			(pintype "passive")
		)
		(pad "11" smd rect
			(at -0.804 2.191)
			(size 0.2 0.45)
			(layers "F.Cu" "F.Mask" "F.Paste")
			(net 1013 "/Recovery USB/USBC2_DIR")
			(pinfunction "DIR")
			(pintype "passive")
		)
		(pad "12" smd rect
			(at -0.403 2.191)
			(size 0.2 0.5)
			(layers "F.Cu" "F.Mask" "F.Paste")
			(net 1021 "/Recovery USB/~{USBC2_EN_MUX}")
			(pinfunction "ENn_MUX")
			(pintype "passive")
		)
		(pad "13" smd rect
			(at -0.003 2.191)
			(size 0.2 0.5)
			(layers "F.Cu" "F.Mask" "F.Paste")
			(net 1 "GND")
			(pinfunction "GND")
			(pintype "passive")
		)
		(pad "14" smd rect
			(at 0.396 2.191)
			(size 0.2 0.5)
			(layers "F.Cu" "F.Mask" "F.Paste")
			(net 800 "/Recovery USB/USBC2_RX1_N")
			(pinfunction "RX1-")
			(pintype "passive")
		)
		(pad "15" smd rect
			(at 0.797 2.191)
			(size 0.2 0.45)
			(layers "F.Cu" "F.Mask" "F.Paste")
			(net 802 "/Recovery USB/USBC2_RX1_P")
			(pinfunction "RX1+")
			(pintype "passive")
		)
		(pad "16" smd rect
			(at 1.222 1.79 90)
			(size 0.2 0.45)
			(layers "F.Cu" "F.Mask" "F.Paste")
			(net 234 "/Recovery USB/USBC2_TX1_N")
			(pinfunction "TX1-")
			(pintype "passive")
		)
		(pad "17" smd rect
			(at 1.196 1.391 90)
			(size 0.2 0.5)
			(layers "F.Cu" "F.Mask" "F.Paste")
			(net 242 "/Recovery USB/USBC2_TX1_P")
			(pinfunction "TX1+")
			(pintype "passive")
		)
		(pad "18" smd rect
			(at 1.196 0.99 90)
			(size 0.2 0.5)
			(layers "F.Cu" "F.Mask" "F.Paste")
			(net 807 "/Recovery USB/USBC2_RX2_N")
			(pinfunction "RX2-")
			(pintype "passive")
		)
		(pad "19" smd rect
			(at 1.196 0.59 90)
			(size 0.2 0.5)
			(layers "F.Cu" "F.Mask" "F.Paste")
			(net 804 "/Recovery USB/USBC2_RX2_P")
			(pinfunction "RX2+")
			(pintype "passive")
		)
		(pad "20" smd rect
			(at 1.196 0.191 90)
			(size 0.2 0.5)
			(layers "F.Cu" "F.Mask" "F.Paste")
			(net 237 "/Recovery USB/USBC2_TX2_N")
			(pinfunction "TX2-")
			(pintype "passive")
		)
		(pad "21" smd rect
			(at 1.196 -0.21 90)
			(size 0.2 0.5)
			(layers "F.Cu" "F.Mask" "F.Paste")
			(net 260 "/Recovery USB/USBC2_TX2_P")
			(pinfunction "TX2+")
			(pintype "passive")
		)
		(pad "22" smd rect
			(at 1.196 -0.609 90)
			(size 0.2 0.5)
			(layers "F.Cu" "F.Mask" "F.Paste")
			(net 1011 "/Recovery USB/USBC2_ADDR")
			(pinfunction "ADDR")
			(pintype "passive")
		)
		(pad "23" smd rect
			(at 1.196 -1.01 90)
			(size 0.2 0.5)
			(layers "F.Cu" "F.Mask" "F.Paste")
			(net 1366 "/Recovery USB/~{USBC2_INT_R}")
			(pinfunction "INT_N/OUT3")
			(pintype "passive")
		)
		(pad "24" smd rect
			(at 1.196 -1.41 90)
			(size 0.2 0.5)
			(layers "F.Cu" "F.Mask" "F.Paste")
			(net 1014 "/Recovery USB/USBC2_FAULT_N")
			(pinfunction "VCONN_FAULT_N")
			(pintype "passive")
		)
		(pad "25" smd rect
			(at 1.222 -1.809 90)
			(size 0.2 0.45)
			(layers "F.Cu" "F.Mask" "F.Paste")
			(net 1024 "/Recovery USB/USBC2_I2C_SDA")
			(pinfunction "SDA/OUT1")
			(pintype "passive")
		)
		(pad "26" smd rect
			(at 0.797 -2.21)
			(size 0.2 0.45)
			(layers "F.Cu" "F.Mask" "F.Paste")
			(net 1025 "/Recovery USB/USBC2_I2C_SCL")
			(pinfunction "SCL/OUT2")
			(pintype "passive")
		)
		(pad "27" smd rect
			(at 0.396 -2.21)
			(size 0.2 0.5)
			(layers "F.Cu" "F.Mask" "F.Paste")
			(net 889 "/Recovery USB/USBC2_ID")
			(pinfunction "ID")
			(pintype "passive")
		)
		(pad "28" smd rect
			(at -0.003 -2.21)
			(size 0.2 0.5)
			(layers "F.Cu" "F.Mask" "F.Paste")
			(net 1 "GND")
			(pinfunction "GND")
			(pintype "passive")
		)
		(pad "29" smd rect
			(at -0.403 -2.21)
			(size 0.2 0.5)
			(layers "F.Cu" "F.Mask" "F.Paste")
			(net 1022 "/Recovery USB/~{USBC2_EN_CC}")
			(pinfunction "ENn_CC")
			(pintype "passive")
		)
		(pad "30" smd rect
			(at -0.804 -2.21)
			(size 0.2 0.45)
			(layers "F.Cu" "F.Mask" "F.Paste")
			(net 5 "+5V")
			(pinfunction "VDD5")
			(pintype "passive")
		)
		(pad "31" smd rect
			(at -0.003 -0.01)
			(size 1.2 3.2)
			(layers "F.Cu" "F.Mask" "F.Paste")
			(net 1 "GND")
			(pinfunction "GND")
			(pintype "passive")
		)
	)
	(footprint "antmicro-footprints:TP_SMD_0.75mm"
		(layer "F.Cu")
		(at 173 57.15 90)
		(property "Reference" "TP9"
			(at -1.49 -0.65875 90)
			(layer "F.SilkS")
			(hide yes)
			(effects
				(font
					(size 0.7 0.7)
					(thickness 0.15)
				)
				(justify left bottom)
			)
		)
		(property "Value" "TP_0.75mm_SMD"
			(at 0 1.2 90)
			(layer "F.Fab")
			(effects
				(font
					(size 0.7 0.7)
					(thickness 0.15)
				)
				(justify left bottom)
			)
		)
		(property "Description" "SMT test point"
			(at 0 0 90)
			(layer "F.Fab")
			(hide yes)
			(effects
				(font
					(size 1.27 1.27)
					(thickness 0.15)
				)
			)
		)
		(property "MPN" ""
			(at 0 0 90)
			(unlocked yes)
			(layer "F.Fab")
			(hide yes)
			(effects
				(font
					(size 1 1)
					(thickness 0.15)
				)
			)
		)
		(property "Manufacturer" ""
			(at 0 0 90)
			(unlocked yes)
			(layer "F.Fab")
			(hide yes)
			(effects
				(font
					(size 1 1)
					(thickness 0.15)
				)
			)
		)
		(property "Author" "Antmicro"
			(at 0 0 90)
			(unlocked yes)
			(layer "F.Fab")
			(hide yes)
			(effects
				(font
					(size 1 1)
					(thickness 0.15)
				)
			)
		)
		(property "License" "Apache-2.0"
			(at 0 0 90)
			(unlocked yes)
			(layer "F.Fab")
			(hide yes)
			(effects
				(font
					(size 1 1)
					(thickness 0.15)
				)
			)
		)
		(sheetname "/Power/")
		(sheetfile "power.kicad_sch")
		(attr exclude_from_pos_files exclude_from_bom)
		(fp_circle
			(center 0 0)
			(end 0.475 0)
			(stroke
				(width 0.05)
				(type default)
			)
			(fill no)
			(layer "F.CrtYd")
		)
		(fp_text user "Author: Antmicro"
			(at -0.4 3.901 90)
			(layer "F.Fab")
			(effects
				(font
					(size 0.7 0.7)
					(thickness 0.15)
				)
				(justify left bottom)
			)
		)
		(fp_text user "${REFERENCE}"
			(at -0.4 2.7 90)
			(layer "F.Fab")
			(effects
				(font
					(size 0.7 0.7)
					(thickness 0.15)
				)
				(justify left bottom)
			)
		)
		(fp_text user "License: Apache-2.0"
			(at -0.4 5.101 90)
			(layer "F.Fab")
			(effects
				(font
					(size 0.7 0.7)
					(thickness 0.15)
				)
				(justify left bottom)
			)
		)
		(pad "1" smd circle
			(at 0 0 90)
			(size 0.75 0.75)
			(layers "F.Cu" "F.Mask")
			(net 491 "+5V_AON")
			(pinfunction "1")
			(pintype "passive")
		)
	)
)
